FILE_TYPE = CONNECTIVITY;
{Allegro Design Entry HDL 17.4-2019 S026 (4007227) 1/17/2022}
"PAGE_NUMBER" = 75;
0"NC";
1"PD_ESPI_CPU1_CLK2";
2"SPI_CPU1_CLK";
3"CLK_CPU1_RTCCLK";
4"PD_ESPI_CPU1_CLK2";
5"GND\g";
6"PVDD18_S5_P0\g";
7"PVDD18_S5_P1\g";
8"GND\g";
9"CLK_CPU1_RTCCLK";
10"CPU0_ROM_TYPE_SELECT";
11"CLK_ESPI_CPU0_CLK1";
12"UART_CPU0_SCM_UART1_TX";
13"CLK_CPU0_RTCCLK";
14"SPI_CPU0_CLK";
15"CLK_CPU0_RTCCLK";
16"CPU0_ROM_TYPE_SELECT";
17"PD_ESPI_CPU0_CLK2";
18"SPI_CPU0_CLK";
19"SPI_CPU1_CLK";
20"CLK_ESPI_CPU0_CLK1";
21"PD_ESPI_CPU0_CLK2";
22"UART_CPU0_SCM_UART1_TX";
%"Q_RES"
"1","(-8650,3600)","0","pure_quanta","I12";
;
LOCATION"R751"
$SEC"1"
CDS_SEC"1"
VALUE"10K"
TOLERANCE"5%"
MATERIAL"CHIP"
PACK_TYPE"0402LF"
WATTAGE"1/16W"
CDS_LIB"pure_quanta"
PART_NUMBER"CS31002JB08";
"B"
$PN"2"15;
"A"
$PN"1"5;
%"UNIVERSAL_GND"
"1","(-8950,2850)","0","pure_quanta_power","I15";
;
CDS_LIB"pure_quanta_power"
HDL_POWER"GND";
"A"5;
%"UNIVERSAL_POWER"
"1","(-8950,5950)","0","pure_quanta_power","I39";
;
HDL_POWER"PVDD18_S5_P0"
CDS_LIB"pure_quanta_power";
"A"6;
%"Q_RES"
"1","(-8650,5450)","0","pure_quanta","I41";
;
LOCATION"R729"
$SEC"1"
CDS_SEC"1"
VALUE"10K"
TOLERANCE"5%"
MATERIAL"EMPTY"
PACK_TYPE"0402LF"
WATTAGE"1/16W"
CDS_LIB"pure_quanta"
PART_NUMBER"CS31002JB08";
"B"
$PN"2"12;
"A"
$PN"1"6;
%"Q_RES"
"1","(-8625,5175)","0","pure_quanta","I43";
;
LOCATION"R737"
$SEC"1"
CDS_SEC"1"
MATERIAL"CHIP"
TOLERANCE"5%"
VALUE"10K"
CDS_LIB"pure_quanta"
WATTAGE"1/16W"
PACK_TYPE"0402LF"
PART_NUMBER"CS31002JB08";
"B"
$PN"2"16;
"A"
$PN"1"6;
%"Q_RES"
"1","(-8625,4800)","0","pure_quanta","I44";
;
LOCATION"R740"
$SEC"1"
CDS_SEC"1"
VALUE"10K"
TOLERANCE"5%"
MATERIAL"EMPTY"
PACK_TYPE"0402LF"
WATTAGE"1/16W"
CDS_LIB"pure_quanta"
PART_NUMBER"CS31002JB08";
"B"
$PN"2"13;
"A"
$PN"1"6;
%"Q_RES"
"1","(-8625,4925)","0","pure_quanta","I45";
;
LOCATION"R739"
$SEC"1"
CDS_SEC"1"
VALUE"10K"
TOLERANCE"5%"
MATERIAL"EMPTY"
PACK_TYPE"0402LF"
WATTAGE"1/16W"
CDS_LIB"pure_quanta"
PART_NUMBER"CS31002JB08";
"B"
$PN"2"11;
"A"
$PN"1"6;
%"Q_RES"
"1","(-8625,4550)","0","pure_quanta","I46";
;
LOCATION"R742"
$SEC"1"
CDS_SEC"1"
VALUE"10K"
TOLERANCE"5%"
MATERIAL"EMPTY"
PACK_TYPE"0402LF"
WATTAGE"1/16W"
CDS_LIB"pure_quanta"
PART_NUMBER"CS31002JB08";
"B"
$PN"2"21;
"A"
$PN"1"6;
%"Q_RES"
"1","(-8650,3725)","0","pure_quanta","I74";
;
LOCATION"R750"
$SEC"1"
CDS_SEC"1"
VALUE"30K"
TOLERANCE"1%"
MATERIAL"CHIP"
CDS_LIB"pure_quanta"
WATTAGE"1/16W"
PACK_TYPE"0402LF"
PART_NUMBER"CS33002FB02";
"B"
$PN"2"20;
"A"
$PN"1"5;
%"Q_RES"
"1","(-8650,3350)","0","pure_quanta","I75";
;
LOCATION"R753"
$SEC"1"
CDS_SEC"1"
VALUE"10K"
MATERIAL"CHIP"
TOLERANCE"5%"
PACK_TYPE"0402LF"
WATTAGE"1/16W"
CDS_LIB"pure_quanta"
PART_NUMBER"CS31002JB08";
"B"
$PN"2"17;
"A"
$PN"1"5;
%"Q_RES"
"1","(-8650,4250)","0","pure_quanta","I8";
;
LOCATION"R747"
$SEC"1"
CDS_SEC"1"
TOLERANCE"1%"
VALUE"1K"
MATERIAL"CHIP"
PACK_TYPE"0402LF"
WATTAGE"1/16W"
CDS_LIB"pure_quanta"
PART_NUMBER"CS21002FB06";
"B"
$PN"2"22;
"A"
$PN"1"5;
%"Q_RES"
"1","(-3950,5550)","0","pure_quanta","I87";
;
LOCATION"R730"
$SEC"1"
CDS_SEC"1"
MATERIAL"CHIP"
VALUE"10K"
TOLERANCE"5%"
CDS_LIB"pure_quanta"
WATTAGE"1/16W"
PACK_TYPE"0402LF"
PART_NUMBER"CS31002JB08";
"B"
$PN"2"19;
"A"
$PN"1"7;
%"UNIVERSAL_POWER"
"1","(-4275,5800)","0","pure_quanta_power","I88";
;
HDL_POWER"PVDD18_S5_P1"
CDS_LIB"pure_quanta_power";
"A"7;
%"Q_RES"
"1","(-3975,5275)","0","pure_quanta","I89";
;
LOCATION"R736"
$SEC"1"
CDS_SEC"1"
MATERIAL"EMPTY"
VALUE"10K"
TOLERANCE"5%"
PACK_TYPE"0402LF"
WATTAGE"1/16W"
CDS_LIB"pure_quanta"
PART_NUMBER"CS31002JB08";
"B"
$PN"2"4;
"A"
$PN"1"7;
%"Q_RES"
"1","(-8650,3975)","0","pure_quanta","I9";
;
LOCATION"R748"
$SEC"1"
CDS_SEC"1"
VALUE"10K"
TOLERANCE"5%"
MATERIAL"EMPTY"
PACK_TYPE"0402LF"
WATTAGE"1/16W"
CDS_LIB"pure_quanta"
PART_NUMBER"CS31002JB08";
"B"
$PN"2"10;
"A"
$PN"1"5;
%"Q_RES"
"1","(-3950,5000)","0","pure_quanta","I90";
;
LOCATION"R1501"
$SEC"1"
CDS_SEC"1"
VALUE"10K"
TOLERANCE"5%"
MATERIAL"EMPTY"
PACK_TYPE"0402LF"
WATTAGE"1/16W"
CDS_LIB"pure_quanta"
PART_NUMBER"CS31002JB08";
"B"
$PN"2"3;
"A"
$PN"1"7;
%"Q_RES"
"1","(-3925,4650)","0","pure_quanta","I91";
;
LOCATION"R754"
$SEC"1"
CDS_SEC"1"
TOLERANCE"5%"
WATTAGE"1/16W"
VALUE"10K"
PACK_TYPE"0402LF"
MATERIAL"EMPTY"
CDS_LIB"pure_quanta"
PART_NUMBER"CS31002JB08";
"B"
$PN"2"2;
"A"
$PN"1"8;
%"Q_RES"
"1","(-3950,4375)","0","pure_quanta","I92";
;
LOCATION"R760"
$SEC"1"
CDS_SEC"1"
VALUE"10K"
TOLERANCE"5%"
MATERIAL"CHIP"
PACK_TYPE"0402LF"
WATTAGE"1/16W"
CDS_LIB"pure_quanta"
PART_NUMBER"CS31002JB08";
"B"
$PN"2"1;
"A"
$PN"1"8;
%"Q_RES"
"1","(-3950,4100)","0","pure_quanta","I94";
;
LOCATION"R1502"
$SEC"1"
CDS_SEC"1"
VALUE"10K"
TOLERANCE"5%"
MATERIAL"CHIP"
PACK_TYPE"0402LF"
WATTAGE"1/16W"
CDS_LIB"pure_quanta"
PART_NUMBER"CS31002JB08";
"B"
$PN"2"9;
"A"
$PN"1"8;
%"UNIVERSAL_GND"
"1","(-4275,3725)","0","pure_quanta_power","I95";
;
CDS_LIB"pure_quanta_power"
HDL_POWER"GND";
"A"8;
%"Q_RES"
"1","(-8625,5725)","0","pure_quanta","I97";
;
LOCATION"R743"
$SEC"1"
CDS_SEC"1"
TOLERANCE"5%"
MATERIAL"CHIP"
VALUE"10K"
PACK_TYPE"0402LF"
WATTAGE"1/16W"
CDS_LIB"pure_quanta"
PART_NUMBER"CS31002JB08";
"B"
$PN"2"18;
"A"
$PN"1"6;
%"Q_RES"
"1","(-8625,3150)","0","pure_quanta","I99";
;
LOCATION"R6098"
$SEC"1"
CDS_SEC"1"
VALUE"10K"
TOLERANCE"5%"
MATERIAL"EMPTY"
CDS_LIB"pure_quanta"
WATTAGE"1/16W"
PACK_TYPE"0402LF"
PART_NUMBER"CS31002JB08";
"B"
$PN"2"14;
"A"
$PN"1"5;
END.
